# BASEBOARD_FAB2 (Tioga Pass) — schematic netlist excerpt (pin names and nets, part order shuffled) for the footprints in the layout excerpt that follows; sources: Cadence DE-HDL packaged netlist, KiCad conversion of Wiwynn_Tioga_Pass_MB.brd

C3N10  CAP_A  22.0UF 4V 20% X6S  pkg 0603V  page 132 : A = PVNN_PCH_STBY ; B = GND
R6P49  RES  2.26K 1.0% EMPTY  pkg 0402  page 213 : A = P3V3_STBY ; B = PU_VR_PVCCIO_CPU1_FAULT1

(kicad_pcb
	(version 20260206)
	(generator "pcbnew")
	(generator_version "10.0")
	(general
		(thickness 1.6)
		(legacy_teardrops no)
	)
	(paper "A4")
	(title_block
		(title "Wiwynn_Tioga_Pass_MB.brd")
		(comment 1 "Tioga Pass / footprints 2932-2933 of 4770")
	)
	(layers
		(0 "F.Cu" signal "TOP")
		(4 "In1.Cu" signal "L2GND")
		(6 "In2.Cu" signal "L3")
		(8 "In3.Cu" signal "L4GND")
		(10 "In4.Cu" signal "L5")
		(12 "In5.Cu" signal "L6GND")
		(14 "In6.Cu" signal "L7VCC")
		(16 "In7.Cu" signal "L8VCC")
		(18 "In8.Cu" signal "L9GND")
		(20 "In9.Cu" signal "L10")
		(22 "In10.Cu" signal "L11GND")
		(24 "In11.Cu" signal "L12")
		(26 "In12.Cu" signal "L13GND")
		(2 "B.Cu" signal "BOTTOM")
		(9 "F.Adhes" user "F.Adhesive")
		(11 "B.Adhes" user "B.Adhesive")
		(13 "F.Paste" user "Package Geometry/Pastemask Top")
		(15 "B.Paste" user "Package Geometry/Pastemask Bottom")
		(5 "F.SilkS" user "Ref Des/Silkscreen Top")
		(7 "B.SilkS" user "Ref Des/Silkscreen Bottom")
		(1 "F.Mask" user "Board Geometry/Soldermask Top")
		(3 "B.Mask" user "Board Geometry/Soldermask Bottom")
		(17 "Dwgs.User" user "User.Drawings")
		(19 "Cmts.User" user "User.Comments")
		(21 "Eco1.User" user "User.Eco1")
		(23 "Eco2.User" user "User.Eco2")
		(25 "Edge.Cuts" user "Board Geometry/Outline")
		(27 "Margin" user)
		(31 "F.CrtYd" user "Package Geometry/Place Bound Top")
		(29 "B.CrtYd" user "Package Geometry/Place Bound Bottom")
		(35 "F.Fab" user "Ref Des/Assembly Top")
		(33 "B.Fab" user "Ref Des/Assembly Bottom")
	)
	(footprint ""
		(layer "B.Cu")
		(at 385.6482 -109.8804 90)
		(property "Reference" "C3N10"
			(at 0 0 90)
			(layer "B.SilkS")
			(hide yes)
			(effects
				(font
					(size 1.27 1.27)
				)
				(justify mirror)
			)
		)
		(property "Value" ""
			(at 0 0 90)
			(layer "B.Fab")
			(effects
				(font
					(size 1.27 1.27)
				)
				(justify mirror)
			)
		)
		(duplicate_pad_numbers_are_jumpers no)
		(fp_rect
			(start 0.499872 1.522476)
			(end -0.500126 -0.277622)
			(stroke
				(width 0)
				(type default)
			)
			(fill no)
			(layer "B.CrtYd")
		)
		(fp_line
			(start 0.499872 -0.277622)
			(end -0.500126 -0.277622)
			(stroke
				(width 0.1)
				(type default)
			)
			(layer "B.Fab")
		)
		(fp_line
			(start -0.500126 -0.277622)
			(end -0.500126 1.522476)
			(stroke
				(width 0.1)
				(type default)
			)
			(layer "B.Fab")
		)
		(fp_line
			(start 0.499872 1.522476)
			(end 0.499872 -0.277622)
			(stroke
				(width 0.1)
				(type default)
			)
			(layer "B.Fab")
		)
		(fp_line
			(start -0.500126 1.522476)
			(end 0.499872 1.522476)
			(stroke
				(width 0.1)
				(type default)
			)
			(layer "B.Fab")
		)
		(pad "1" smd custom
			(at 0 0)
			(size 0.18415 0.18415)
			(layers "B.Cu" "B.Mask" "B.Paste")
			(net "PVNN_PCH_STBY")
			(options
				(clearance outline)
				(anchor circle)
			)
			(primitives
				(gr_poly
					(pts
						(arc
							(start -0.3683 0.2794)
							(mid -0.338542 0.351242)
							(end -0.2667 0.381)
						)
						(arc
							(start 0.2667 0.381)
							(mid 0.338542 0.351242)
							(end 0.3683 0.2794)
						)
						(arc
							(start 0.3683 -0.2794)
							(mid 0.338542 -0.351242)
							(end 0.2667 -0.381)
						)
						(arc
							(start -0.2667 -0.381)
							(mid -0.338542 -0.351242)
							(end -0.3683 -0.2794)
						)
					)
					(width 0)
					(fill yes)
				)
			)
		)
		(pad "2" smd custom
			(at 0 1.2446)
			(size 0.18415 0.18415)
			(layers "B.Cu" "B.Mask" "B.Paste")
			(net "GND")
			(options
				(clearance outline)
				(anchor circle)
			)
			(primitives
				(gr_poly
					(pts
						(arc
							(start -0.3683 0.2794)
							(mid -0.338542 0.351242)
							(end -0.2667 0.381)
						)
						(arc
							(start 0.2667 0.381)
							(mid 0.338542 0.351242)
							(end 0.3683 0.2794)
						)
						(arc
							(start 0.3683 -0.2794)
							(mid 0.338542 -0.351242)
							(end 0.2667 -0.381)
						)
						(arc
							(start -0.2667 -0.381)
							(mid -0.338542 -0.351242)
							(end -0.3683 -0.2794)
						)
					)
					(width 0)
					(fill yes)
				)
			)
		)
		(zone
			(layer "B.Cu")
			(hatch none 0.5)
			(connect_pads
				(clearance 0)
			)
			(min_thickness 0.25)
			(keepout
				(tracks not_allowed)
				(vias allowed)
				(pads allowed)
				(copperpour not_allowed)
				(footprints allowed)
			)
			(placement
				(enabled no)
				(sheetname "")
			)
			(fill
				(thermal_gap 0.5)
				(thermal_bridge_width 0.5)
				(island_removal_mode 0)
			)
			(polygon
				(pts
					(xy 386.5245 -110.2614) (xy 386.0165 -110.2614) (xy 386.0165 -109.4994) (xy 386.5245 -109.4994)
				)
			)
		)
		(zone
			(layer "B.Cu")
			(hatch none 0.5)
			(connect_pads
				(clearance 0)
			)
			(min_thickness 0.25)
			(keepout
				(tracks allowed)
				(vias not_allowed)
				(pads allowed)
				(copperpour not_allowed)
				(footprints allowed)
			)
			(placement
				(enabled no)
				(sheetname "")
			)
			(fill
				(thermal_gap 0.5)
				(thermal_bridge_width 0.5)
				(island_removal_mode 0)
			)
			(polygon
				(pts
					(xy 386.5245 -110.2614) (xy 386.0165 -110.2614) (xy 386.0165 -109.4994) (xy 386.5245 -109.4994)
				)
			)
		)
	)
	(footprint ""
		(layer "B.Cu")
		(at 174.371 -65.024 -90)
		(property "Reference" "R6P49"
			(at 0 0 90)
			(layer "B.SilkS")
			(hide yes)
			(effects
				(font
					(size 1.27 1.27)
				)
				(justify mirror)
			)
		)
		(property "Value" ""
			(at 0 0 90)
			(layer "B.Fab")
			(effects
				(font
					(size 1.27 1.27)
				)
				(justify mirror)
			)
		)
		(duplicate_pad_numbers_are_jumpers no)
		(fp_poly
			(pts
				(xy 0.2794 -0.1016) (xy -0.2794 -0.1016) (xy -0.2794 0.9906) (xy 0.2794 0.9906)
			)
			(stroke
				(width 0)
				(type default)
			)
			(fill no)
			(layer "B.CrtYd")
		)
		(fp_line
			(start -0.2794 0.9906)
			(end -0.2794 -0.1016)
			(stroke
				(width 0.1)
				(type default)
			)
			(layer "B.Fab")
		)
		(fp_line
			(start 0.2794 0.9906)
			(end -0.2794 0.9906)
			(stroke
				(width 0.1)
				(type default)
			)
			(layer "B.Fab")
		)
		(fp_line
			(start -0.2794 -0.1016)
			(end 0.2794 -0.1016)
			(stroke
				(width 0.1)
				(type default)
			)
			(layer "B.Fab")
		)
		(fp_line
			(start 0.2794 -0.1016)
			(end 0.2794 0.9906)
			(stroke
				(width 0.1)
				(type default)
			)
			(layer "B.Fab")
		)
		(pad "1" smd rect
			(at 0 0 90)
			(size 0.508 0.508)
			(layers "B.Cu" "B.Mask" "B.Paste")
			(net "P3V3_STBY")
		)
		(pad "2" smd rect
			(at 0 0.889 90)
			(size 0.508 0.508)
			(layers "B.Cu" "B.Mask" "B.Paste")
			(net "PU_VR_PVCCIO_CPU1_FAULT1")
		)
		(zone
			(layer "B.Cu")
			(hatch none 0.5)
			(connect_pads
				(clearance 0)
			)
			(min_thickness 0.25)
			(keepout
				(tracks not_allowed)
				(vias allowed)
				(pads allowed)
				(copperpour not_allowed)
				(footprints allowed)
			)
			(placement
				(enabled no)
				(sheetname "")
			)
			(fill
				(thermal_gap 0.5)
				(thermal_bridge_width 0.5)
				(island_removal_mode 0)
			)
			(polygon
				(pts
					(xy 173.736 -64.77) (xy 173.736 -65.278) (xy 174.117 -65.278) (xy 174.117 -64.77)
				)
			)
		)
		(zone
			(layer "B.Cu")
			(hatch none 0.5)
			(connect_pads
				(clearance 0)
			)
			(min_thickness 0.25)
			(keepout
				(tracks allowed)
				(vias not_allowed)
				(pads allowed)
				(copperpour not_allowed)
				(footprints allowed)
			)
			(placement
				(enabled no)
				(sheetname "")
			)
			(fill
				(thermal_gap 0.5)
				(thermal_bridge_width 0.5)
				(island_removal_mode 0)
			)
			(polygon
				(pts
					(xy 174.117 -64.77) (xy 174.117 -65.278) (xy 173.736 -65.278) (xy 173.736 -64.77)
				)
			)
		)
	)
)
